(kicad_pcb
	(version 20260206)
	(generator "pcbnew")
	(generator_version "10.0")
	(general
		(thickness 1.6)
		(legacy_teardrops no)
	)
	(paper "A4")
	(title_block
		(title "01162023_DA0F0TEBIF0_F0T_Expander_BD_F_brd_V02_OCP.brd")
		(comment 1 "Grand Teton / footprints 8397-8404 of 9728")
	)
	(layers
		(0 "F.Cu" signal "TOP")
		(4 "In1.Cu" signal "GND")
		(6 "In2.Cu" signal "VCC")
		(8 "In3.Cu" signal "VCC1")
		(10 "In4.Cu" signal "GND1")
		(12 "In5.Cu" signal "IN1")
		(14 "In6.Cu" signal "GND2")
		(16 "In7.Cu" signal "IN2")
		(18 "In8.Cu" signal "GND3")
		(20 "In9.Cu" signal "IN3")
		(22 "In10.Cu" signal "GND4")
		(24 "In11.Cu" signal "IN4")
		(26 "In12.Cu" signal "GND5")
		(28 "In13.Cu" signal "IN5")
		(30 "In14.Cu" signal "GND6")
		(32 "In15.Cu" signal "IN6")
		(34 "In16.Cu" signal "GND7")
		(2 "B.Cu" signal "BOTTOM")
		(9 "F.Adhes" user "F.Adhesive")
		(11 "B.Adhes" user "B.Adhesive")
		(13 "F.Paste" user "Package Geometry/Pastemask Top")
		(15 "B.Paste" user "Package Geometry/Pastemask Bottom")
		(5 "F.SilkS" user "Ref Des/Silkscreen Top")
		(7 "B.SilkS" user "Ref Des/Silkscreen Bottom")
		(1 "F.Mask" user "Board Geometry/Soldermask Top")
		(3 "B.Mask" user "Board Geometry/Soldermask Bottom")
		(17 "Dwgs.User" user "User.Drawings")
		(19 "Cmts.User" user "User.Comments")
		(21 "Eco1.User" user "User.Eco1")
		(23 "Eco2.User" user "User.Eco2")
		(25 "Edge.Cuts" user "Board Geometry/Outline")
		(27 "Margin" user)
		(31 "F.CrtYd" user "Package Geometry/Place Bound Top")
		(29 "B.CrtYd" user "Package Geometry/Place Bound Bottom")
		(35 "F.Fab" user "Ref Des/Assembly Top")
		(33 "B.Fab" user "Ref Des/Assembly Bottom")
	)
	(footprint ""
		(layer "B.Cu")
		(at 414.124902 -297.79976 90)
		(property "Reference" "C1889"
			(at 0 0 90)
			(layer "B.SilkS")
			(hide yes)
			(effects
				(font
					(size 1.27 1.27)
				)
				(justify mirror)
			)
		)
		(property "Value" ""
			(at 0 0 90)
			(layer "B.Fab")
			(effects
				(font
					(size 1.27 1.27)
				)
				(justify mirror)
			)
		)
		(duplicate_pad_numbers_are_jumpers no)
		(fp_line
			(start 0.299974 -0.150114)
			(end -0.299974 -0.150114)
			(stroke
				(width 0.1)
				(type default)
			)
			(layer "B.Fab")
		)
		(fp_line
			(start -0.299974 -0.150114)
			(end -0.299974 0.150114)
			(stroke
				(width 0.1)
				(type default)
			)
			(layer "B.Fab")
		)
		(fp_line
			(start 0.299974 0.150114)
			(end 0.299974 -0.150114)
			(stroke
				(width 0.1)
				(type default)
			)
			(layer "B.Fab")
		)
		(fp_line
			(start -0.299974 0.150114)
			(end 0.299974 0.150114)
			(stroke
				(width 0.1)
				(type default)
			)
			(layer "B.Fab")
		)
		(pad "1" smd rect
			(at 0.2667 0 270)
			(size 0.3048 0.381)
			(layers "B.Cu" "B.Mask" "B.Paste")
			(net "P0V8_PEX3")
		)
		(pad "2" smd rect
			(at -0.2667 0 270)
			(size 0.3048 0.381)
			(layers "B.Cu" "B.Mask" "B.Paste")
			(net "GND")
		)
	)
	(footprint ""
		(layer "B.Cu")
		(at 380.762002 -222.590106 180)
		(property "Reference" "C2604"
			(at 0 0 0)
			(layer "B.SilkS")
			(hide yes)
			(effects
				(font
					(size 1.27 1.27)
				)
				(justify mirror)
			)
		)
		(property "Value" ""
			(at 0 0 0)
			(layer "B.Fab")
			(effects
				(font
					(size 1.27 1.27)
				)
				(justify mirror)
			)
		)
		(duplicate_pad_numbers_are_jumpers no)
		(fp_line
			(start 0.7874 0.4064)
			(end 0.7874 -0.4064)
			(stroke
				(width 0.1524)
				(type default)
			)
			(layer "B.SilkS")
		)
		(fp_line
			(start 0.7874 -0.4064)
			(end -0.7874 -0.4064)
			(stroke
				(width 0.1524)
				(type default)
			)
			(layer "B.SilkS")
		)
		(fp_line
			(start -0.7874 0.4064)
			(end 0.7874 0.4064)
			(stroke
				(width 0.1524)
				(type default)
			)
			(layer "B.SilkS")
		)
		(fp_line
			(start -0.7874 -0.4064)
			(end -0.7874 0.4064)
			(stroke
				(width 0.1524)
				(type default)
			)
			(layer "B.SilkS")
		)
		(fp_line
			(start 0.67945 0.3048)
			(end 0.67945 -0.305054)
			(stroke
				(width 0.1)
				(type default)
			)
			(layer "B.Fab")
		)
		(fp_line
			(start 0.67945 -0.305054)
			(end 0.12065 -0.305054)
			(stroke
				(width 0.1)
				(type default)
			)
			(layer "B.Fab")
		)
		(fp_line
			(start 0.12065 0.3048)
			(end 0.67945 0.3048)
			(stroke
				(width 0.1)
				(type default)
			)
			(layer "B.Fab")
		)
		(fp_line
			(start 0.12065 0.2794)
			(end 0.12065 0.3048)
			(stroke
				(width 0.1)
				(type default)
			)
			(layer "B.Fab")
		)
		(fp_line
			(start 0.12065 -0.2794)
			(end -0.12065 -0.2794)
			(stroke
				(width 0.1)
				(type default)
			)
			(layer "B.Fab")
		)
		(fp_line
			(start 0.12065 -0.305054)
			(end 0.12065 -0.2794)
			(stroke
				(width 0.1)
				(type default)
			)
			(layer "B.Fab")
		)
		(fp_line
			(start -0.120396 0.3048)
			(end -0.120396 0.2794)
			(stroke
				(width 0.1)
				(type default)
			)
			(layer "B.Fab")
		)
		(fp_line
			(start -0.120396 0.2794)
			(end 0.12065 0.2794)
			(stroke
				(width 0.1)
				(type default)
			)
			(layer "B.Fab")
		)
		(fp_line
			(start -0.12065 -0.2794)
			(end -0.12065 -0.3048)
			(stroke
				(width 0.1)
				(type default)
			)
			(layer "B.Fab")
		)
		(fp_line
			(start -0.12065 -0.3048)
			(end -0.67945 -0.3048)
			(stroke
				(width 0.1)
				(type default)
			)
			(layer "B.Fab")
		)
		(fp_line
			(start -0.67945 0.3048)
			(end -0.120396 0.3048)
			(stroke
				(width 0.1)
				(type default)
			)
			(layer "B.Fab")
		)
		(fp_line
			(start -0.67945 -0.3048)
			(end -0.67945 0.3048)
			(stroke
				(width 0.1)
				(type default)
			)
			(layer "B.Fab")
		)
		(pad "1" smd circle
			(at 0.40005 0)
			(size 0 0)
			(layers "B.Cu" "B.Mask" "B.Paste")
			(net "GND")
		)
		(pad "2" smd circle
			(at -0.40005 0)
			(size 0 0)
			(layers "B.Cu" "B.Mask" "B.Paste")
			(net "P3V3_AUX")
		)
	)
	(footprint ""
		(layer "B.Cu")
		(at 363.093 -227.965 180)
		(property "Reference" "R3507"
			(at 0 0 0)
			(layer "B.SilkS")
			(hide yes)
			(effects
				(font
					(size 1.27 1.27)
				)
				(justify mirror)
			)
		)
		(property "Value" ""
			(at 0 0 0)
			(layer "B.Fab")
			(effects
				(font
					(size 1.27 1.27)
				)
				(justify mirror)
			)
		)
		(duplicate_pad_numbers_are_jumpers no)
		(fp_line
			(start 0.7874 0.4064)
			(end 0.7874 -0.4064)
			(stroke
				(width 0.1524)
				(type default)
			)
			(layer "B.SilkS")
		)
		(fp_line
			(start 0.7874 -0.4064)
			(end -0.7874 -0.4064)
			(stroke
				(width 0.1524)
				(type default)
			)
			(layer "B.SilkS")
		)
		(fp_line
			(start -0.7874 0.4064)
			(end 0.7874 0.4064)
			(stroke
				(width 0.1524)
				(type default)
			)
			(layer "B.SilkS")
		)
		(fp_line
			(start -0.7874 -0.4064)
			(end -0.7874 0.4064)
			(stroke
				(width 0.1524)
				(type default)
			)
			(layer "B.SilkS")
		)
		(fp_line
			(start 0.67945 0.3048)
			(end 0.67945 -0.305054)
			(stroke
				(width 0.1)
				(type default)
			)
			(layer "B.Fab")
		)
		(fp_line
			(start 0.67945 -0.305054)
			(end 0.12065 -0.305054)
			(stroke
				(width 0.1)
				(type default)
			)
			(layer "B.Fab")
		)
		(fp_line
			(start 0.12065 0.3048)
			(end 0.67945 0.3048)
			(stroke
				(width 0.1)
				(type default)
			)
			(layer "B.Fab")
		)
		(fp_line
			(start 0.12065 0.2794)
			(end 0.12065 0.3048)
			(stroke
				(width 0.1)
				(type default)
			)
			(layer "B.Fab")
		)
		(fp_line
			(start 0.12065 -0.2794)
			(end -0.12065 -0.2794)
			(stroke
				(width 0.1)
				(type default)
			)
			(layer "B.Fab")
		)
		(fp_line
			(start 0.12065 -0.305054)
			(end 0.12065 -0.2794)
			(stroke
				(width 0.1)
				(type default)
			)
			(layer "B.Fab")
		)
		(fp_line
			(start -0.120396 0.3048)
			(end -0.120396 0.2794)
			(stroke
				(width 0.1)
				(type default)
			)
			(layer "B.Fab")
		)
		(fp_line
			(start -0.120396 0.2794)
			(end 0.12065 0.2794)
			(stroke
				(width 0.1)
				(type default)
			)
			(layer "B.Fab")
		)
		(fp_line
			(start -0.12065 -0.2794)
			(end -0.12065 -0.3048)
			(stroke
				(width 0.1)
				(type default)
			)
			(layer "B.Fab")
		)
		(fp_line
			(start -0.12065 -0.3048)
			(end -0.67945 -0.3048)
			(stroke
				(width 0.1)
				(type default)
			)
			(layer "B.Fab")
		)
		(fp_line
			(start -0.67945 0.3048)
			(end -0.120396 0.3048)
			(stroke
				(width 0.1)
				(type default)
			)
			(layer "B.Fab")
		)
		(fp_line
			(start -0.67945 -0.3048)
			(end -0.67945 0.3048)
			(stroke
				(width 0.1)
				(type default)
			)
			(layer "B.Fab")
		)
		(pad "1" smd circle
			(at 0.40005 0)
			(size 0 0)
			(layers "B.Cu" "B.Mask" "B.Paste")
			(net "SPI_PEX3_SDIO2_R1")
		)
		(pad "2" smd circle
			(at -0.40005 0)
			(size 0 0)
			(layers "B.Cu" "B.Mask" "B.Paste")
			(net "GND")
		)
	)
	(footprint ""
		(layer "B.Cu")
		(at 421.249856 -294.94988 180)
		(property "Reference" "C3470"
			(at 0 0 0)
			(layer "B.SilkS")
			(hide yes)
			(effects
				(font
					(size 1.27 1.27)
				)
				(justify mirror)
			)
		)
		(property "Value" ""
			(at 0 0 0)
			(layer "B.Fab")
			(effects
				(font
					(size 1.27 1.27)
				)
				(justify mirror)
			)
		)
		(duplicate_pad_numbers_are_jumpers no)
		(fp_line
			(start 0.299974 0.150114)
			(end 0.299974 -0.150114)
			(stroke
				(width 0.1)
				(type default)
			)
			(layer "B.Fab")
		)
		(fp_line
			(start 0.299974 -0.150114)
			(end -0.299974 -0.150114)
			(stroke
				(width 0.1)
				(type default)
			)
			(layer "B.Fab")
		)
		(fp_line
			(start -0.299974 0.150114)
			(end 0.299974 0.150114)
			(stroke
				(width 0.1)
				(type default)
			)
			(layer "B.Fab")
		)
		(fp_line
			(start -0.299974 -0.150114)
			(end -0.299974 0.150114)
			(stroke
				(width 0.1)
				(type default)
			)
			(layer "B.Fab")
		)
		(pad "1" smd rect
			(at 0.2667 0)
			(size 0.3048 0.381)
			(layers "B.Cu" "B.Mask" "B.Paste")
			(net "P1V25_SERDES_VDDPLL_PEX3")
		)
		(pad "2" smd rect
			(at -0.2667 0)
			(size 0.3048 0.381)
			(layers "B.Cu" "B.Mask" "B.Paste")
			(net "GND")
		)
	)
	(footprint ""
		(layer "B.Cu")
		(at 394.65504 -293.52494)
		(property "Reference" "C3579"
			(at 0 0 0)
			(layer "B.SilkS")
			(hide yes)
			(effects
				(font
					(size 1.27 1.27)
				)
				(justify mirror)
			)
		)
		(property "Value" ""
			(at 0 0 0)
			(layer "B.Fab")
			(effects
				(font
					(size 1.27 1.27)
				)
				(justify mirror)
			)
		)
		(duplicate_pad_numbers_are_jumpers no)
		(fp_line
			(start -0.299974 -0.150114)
			(end -0.299974 0.150114)
			(stroke
				(width 0.1)
				(type default)
			)
			(layer "B.Fab")
		)
		(fp_line
			(start -0.299974 0.150114)
			(end 0.299974 0.150114)
			(stroke
				(width 0.1)
				(type default)
			)
			(layer "B.Fab")
		)
		(fp_line
			(start 0.299974 -0.150114)
			(end -0.299974 -0.150114)
			(stroke
				(width 0.1)
				(type default)
			)
			(layer "B.Fab")
		)
		(fp_line
			(start 0.299974 0.150114)
			(end 0.299974 -0.150114)
			(stroke
				(width 0.1)
				(type default)
			)
			(layer "B.Fab")
		)
		(pad "1" smd rect
			(at 0.2667 0 180)
			(size 0.3048 0.381)
			(layers "B.Cu" "B.Mask" "B.Paste")
			(net "PCEPLL6_VDDA18_PEX3")
		)
		(pad "2" smd rect
			(at -0.2667 0 180)
			(size 0.3048 0.381)
			(layers "B.Cu" "B.Mask" "B.Paste")
			(net "GND")
		)
	)
	(footprint ""
		(layer "B.Cu")
		(at 406.540208 -297.79976 -90)
		(property "Reference" "C1898"
			(at 0 0 90)
			(layer "B.SilkS")
			(hide yes)
			(effects
				(font
					(size 1.27 1.27)
				)
				(justify mirror)
			)
		)
		(property "Value" ""
			(at 0 0 90)
			(layer "B.Fab")
			(effects
				(font
					(size 1.27 1.27)
				)
				(justify mirror)
			)
		)
		(duplicate_pad_numbers_are_jumpers no)
		(fp_line
			(start -0.299974 0.150114)
			(end 0.299974 0.150114)
			(stroke
				(width 0.1)
				(type default)
			)
			(layer "B.Fab")
		)
		(fp_line
			(start 0.299974 0.150114)
			(end 0.299974 -0.150114)
			(stroke
				(width 0.1)
				(type default)
			)
			(layer "B.Fab")
		)
		(fp_line
			(start -0.299974 -0.150114)
			(end -0.299974 0.150114)
			(stroke
				(width 0.1)
				(type default)
			)
			(layer "B.Fab")
		)
		(fp_line
			(start 0.299974 -0.150114)
			(end -0.299974 -0.150114)
			(stroke
				(width 0.1)
				(type default)
			)
			(layer "B.Fab")
		)
		(pad "1" smd rect
			(at 0.2667 0 90)
			(size 0.3048 0.381)
			(layers "B.Cu" "B.Mask" "B.Paste")
			(net "P0V8_PEX3")
		)
		(pad "2" smd rect
			(at -0.2667 0 90)
			(size 0.3048 0.381)
			(layers "B.Cu" "B.Mask" "B.Paste")
			(net "GND")
		)
	)
	(footprint ""
		(layer "B.Cu")
		(at 233.380026 -94.074234 90)
		(property "Reference" "C2614"
			(at 0 0 90)
			(layer "B.SilkS")
			(hide yes)
			(effects
				(font
					(size 1.27 1.27)
				)
				(justify mirror)
			)
		)
		(property "Value" ""
			(at 0 0 90)
			(layer "B.Fab")
			(effects
				(font
					(size 1.27 1.27)
				)
				(justify mirror)
			)
		)
		(duplicate_pad_numbers_are_jumpers no)
		(fp_line
			(start 0.7874 -0.4064)
			(end -0.7874 -0.4064)
			(stroke
				(width 0.1524)
				(type default)
			)
			(layer "B.SilkS")
		)
		(fp_line
			(start -0.7874 -0.4064)
			(end -0.7874 0.4064)
			(stroke
				(width 0.1524)
				(type default)
			)
			(layer "B.SilkS")
		)
		(fp_line
			(start 0.7874 0.4064)
			(end 0.7874 -0.4064)
			(stroke
				(width 0.1524)
				(type default)
			)
			(layer "B.SilkS")
		)
		(fp_line
			(start -0.7874 0.4064)
			(end 0.7874 0.4064)
			(stroke
				(width 0.1524)
				(type default)
			)
			(layer "B.SilkS")
		)
		(fp_line
			(start 0.67945 -0.305054)
			(end 0.12065 -0.305054)
			(stroke
				(width 0.1)
				(type default)
			)
			(layer "B.Fab")
		)
		(fp_line
			(start 0.12065 -0.305054)
			(end 0.12065 -0.2794)
			(stroke
				(width 0.1)
				(type default)
			)
			(layer "B.Fab")
		)
		(fp_line
			(start -0.12065 -0.3048)
			(end -0.67945 -0.3048)
			(stroke
				(width 0.1)
				(type default)
			)
			(layer "B.Fab")
		)
		(fp_line
			(start -0.67945 -0.3048)
			(end -0.67945 0.3048)
			(stroke
				(width 0.1)
				(type default)
			)
			(layer "B.Fab")
		)
		(fp_line
			(start 0.12065 -0.2794)
			(end -0.12065 -0.2794)
			(stroke
				(width 0.1)
				(type default)
			)
			(layer "B.Fab")
		)
		(fp_line
			(start -0.12065 -0.2794)
			(end -0.12065 -0.3048)
			(stroke
				(width 0.1)
				(type default)
			)
			(layer "B.Fab")
		)
		(fp_line
			(start 0.12065 0.2794)
			(end 0.12065 0.3048)
			(stroke
				(width 0.1)
				(type default)
			)
			(layer "B.Fab")
		)
		(fp_line
			(start -0.120396 0.2794)
			(end 0.12065 0.2794)
			(stroke
				(width 0.1)
				(type default)
			)
			(layer "B.Fab")
		)
		(fp_line
			(start 0.67945 0.3048)
			(end 0.67945 -0.305054)
			(stroke
				(width 0.1)
				(type default)
			)
			(layer "B.Fab")
		)
		(fp_line
			(start 0.12065 0.3048)
			(end 0.67945 0.3048)
			(stroke
				(width 0.1)
				(type default)
			)
			(layer "B.Fab")
		)
		(fp_line
			(start -0.120396 0.3048)
			(end -0.120396 0.2794)
			(stroke
				(width 0.1)
				(type default)
			)
			(layer "B.Fab")
		)
		(fp_line
			(start -0.67945 0.3048)
			(end -0.120396 0.3048)
			(stroke
				(width 0.1)
				(type default)
			)
			(layer "B.Fab")
		)
		(pad "1" smd circle
			(at 0.40005 0 270)
			(size 0 0)
			(layers "B.Cu" "B.Mask" "B.Paste")
			(net "P3V3_PEX_USB_HUB")
		)
		(pad "2" smd circle
			(at -0.40005 0 270)
			(size 0 0)
			(layers "B.Cu" "B.Mask" "B.Paste")
			(net "GND")
		)
	)
	(footprint ""
		(layer "B.Cu")
		(at 366.268 -235.458 180)
		(property "Reference" "R909"
			(at 0 0 0)
			(layer "B.SilkS")
			(hide yes)
			(effects
				(font
					(size 1.27 1.27)
				)
				(justify mirror)
			)
		)
		(property "Value" ""
			(at 0 0 0)
			(layer "B.Fab")
			(effects
				(font
					(size 1.27 1.27)
				)
				(justify mirror)
			)
		)
		(duplicate_pad_numbers_are_jumpers no)
		(fp_line
			(start 0.7874 0.4064)
			(end 0.7874 -0.4064)
			(stroke
				(width 0.1524)
				(type default)
			)
			(layer "B.SilkS")
		)
		(fp_line
			(start 0.7874 -0.4064)
			(end -0.7874 -0.4064)
			(stroke
				(width 0.1524)
				(type default)
			)
			(layer "B.SilkS")
		)
		(fp_line
			(start -0.7874 0.4064)
			(end 0.7874 0.4064)
			(stroke
				(width 0.1524)
				(type default)
			)
			(layer "B.SilkS")
		)
		(fp_line
			(start -0.7874 -0.4064)
			(end -0.7874 0.4064)
			(stroke
				(width 0.1524)
				(type default)
			)
			(layer "B.SilkS")
		)
		(fp_line
			(start 0.67945 0.3048)
			(end 0.67945 -0.305054)
			(stroke
				(width 0.1)
				(type default)
			)
			(layer "B.Fab")
		)
		(fp_line
			(start 0.67945 -0.305054)
			(end 0.12065 -0.305054)
			(stroke
				(width 0.1)
				(type default)
			)
			(layer "B.Fab")
		)
		(fp_line
			(start 0.12065 0.3048)
			(end 0.67945 0.3048)
			(stroke
				(width 0.1)
				(type default)
			)
			(layer "B.Fab")
		)
		(fp_line
			(start 0.12065 0.2794)
			(end 0.12065 0.3048)
			(stroke
				(width 0.1)
				(type default)
			)
			(layer "B.Fab")
		)
		(fp_line
			(start 0.12065 -0.2794)
			(end -0.12065 -0.2794)
			(stroke
				(width 0.1)
				(type default)
			)
			(layer "B.Fab")
		)
		(fp_line
			(start 0.12065 -0.305054)
			(end 0.12065 -0.2794)
			(stroke
				(width 0.1)
				(type default)
			)
			(layer "B.Fab")
		)
		(fp_line
			(start -0.120396 0.3048)
			(end -0.120396 0.2794)
			(stroke
				(width 0.1)
				(type default)
			)
			(layer "B.Fab")
		)
		(fp_line
			(start -0.120396 0.2794)
			(end 0.12065 0.2794)
			(stroke
				(width 0.1)
				(type default)
			)
			(layer "B.Fab")
		)
		(fp_line
			(start -0.12065 -0.2794)
			(end -0.12065 -0.3048)
			(stroke
				(width 0.1)
				(type default)
			)
			(layer "B.Fab")
		)
		(fp_line
			(start -0.12065 -0.3048)
			(end -0.67945 -0.3048)
			(stroke
				(width 0.1)
				(type default)
			)
			(layer "B.Fab")
		)
		(fp_line
			(start -0.67945 0.3048)
			(end -0.120396 0.3048)
			(stroke
				(width 0.1)
				(type default)
			)
			(layer "B.Fab")
		)
		(fp_line
			(start -0.67945 -0.3048)
			(end -0.67945 0.3048)
			(stroke
				(width 0.1)
				(type default)
			)
			(layer "B.Fab")
		)
		(pad "1" smd circle
			(at 0.40005 0)
			(size 0 0)
			(layers "B.Cu" "B.Mask" "B.Paste")
			(net "FT4232_SDB_EEPROM_DO")
		)
		(pad "2" smd circle
			(at -0.40005 0)
			(size 0 0)
			(layers "B.Cu" "B.Mask" "B.Paste")
			(net "P3V3_AUX")
		)
	)
)
